(kicad_pcb
	(version 20260206)
	(generator "pcbnew")
	(generator_version "10.0")
	(general
		(thickness 1.6)
		(legacy_teardrops no)
	)
	(paper "A4")
	(title_block
		(title "03242023_DA0F0TMBIJ0_F0T_Motherboard_J_brd_V01_OCP.brd")
		(comment 1 "Grand Teton / footprint 1236 of 6105 (J1), pads 225-291 of 291")
	)
	(layers
		(0 "F.Cu" signal "TOP")
		(4 "In1.Cu" signal "GND")
		(6 "In2.Cu" signal "IN1")
		(8 "In3.Cu" signal "GND1")
		(10 "In4.Cu" signal "IN2")
		(12 "In5.Cu" signal "GND2")
		(14 "In6.Cu" signal "IN3")
		(16 "In7.Cu" signal "GND3")
		(18 "In8.Cu" signal "VCC")
		(20 "In9.Cu" signal "VCC1")
		(22 "In10.Cu" signal "GND4")
		(24 "In11.Cu" signal "IN4")
		(26 "In12.Cu" signal "GND5")
		(28 "In13.Cu" signal "IN5")
		(30 "In14.Cu" signal "GND6")
		(32 "In15.Cu" signal "IN6")
		(34 "In16.Cu" signal "GND7")
		(2 "B.Cu" signal "BOTTOM")
		(9 "F.Adhes" user "F.Adhesive")
		(11 "B.Adhes" user "B.Adhesive")
		(13 "F.Paste" user "Package Geometry/Pastemask Top")
		(15 "B.Paste" user "Package Geometry/Pastemask Bottom")
		(5 "F.SilkS" user "Ref Des/Silkscreen Top")
		(7 "B.SilkS" user "Ref Des/Silkscreen Bottom")
		(1 "F.Mask" user "Board Geometry/Soldermask Top")
		(3 "B.Mask" user "Board Geometry/Soldermask Bottom")
		(17 "Dwgs.User" user "User.Drawings")
		(19 "Cmts.User" user "User.Comments")
		(21 "Eco1.User" user "User.Eco1")
		(23 "Eco2.User" user "User.Eco2")
		(25 "Edge.Cuts" user "Board Geometry/Outline")
		(27 "Margin" user)
		(31 "F.CrtYd" user "Package Geometry/Place Bound Top")
		(29 "B.CrtYd" user "Package Geometry/Place Bound Bottom")
		(35 "F.Fab" user "Ref Des/Assembly Top")
		(33 "B.Fab" user "Ref Des/Assembly Bottom")
	)
	(footprint ""
		(layer "F.Cu")
		(at 303.393348 -258.091686)
		(property "Reference" "J1"
			(at -3.683 -81.702148 0)
			(unlocked yes)
			(layer "F.SilkS")
			(effects
				(font
					(size 0.7874 0.5842)
					(thickness 0.1524)
				)
				(justify left)
			)
		)
		(property "Value" ""
			(at 0 0 0)
			(layer "F.Fab")
			(effects
				(font
					(size 1.27 1.27)
				)
			)
		)
		(duplicate_pad_numbers_are_jumpers no)
		(pad "225" smd rect
			(at 2.050034 9.774936 270)
			(size 0.519938 1.4986)
			(layers "F.Cu" "F.Mask" "F.Paste")
			(net "M_A_CPU0_SB_CA<5>")
		)
		(pad "226" smd rect
			(at 2.050034 10.625074 270)
			(size 0.519938 1.4986)
			(layers "F.Cu" "F.Mask" "F.Paste")
			(net "GND")
		)
		(pad "227" smd rect
			(at 2.050034 11.474958 270)
			(size 0.519938 1.4986)
			(layers "F.Cu" "F.Mask" "F.Paste")
			(net "M_A_CPU0_SB_PAR")
		)
		(pad "228" smd rect
			(at 2.050034 12.325096 270)
			(size 0.519938 1.4986)
			(layers "F.Cu" "F.Mask" "F.Paste")
			(net "GND")
		)
		(pad "229" smd rect
			(at 2.050034 13.17498 270)
			(size 0.519938 1.4986)
			(layers "F.Cu" "F.Mask" "F.Paste")
			(net "M_A_CPU0_SB_CS_N<1>")
		)
		(pad "230" smd rect
			(at 2.050034 14.025118 270)
			(size 0.519938 1.4986)
			(layers "F.Cu" "F.Mask" "F.Paste")
			(net "GND")
		)
		(pad "231" smd rect
			(at 2.050034 14.875002 270)
			(size 0.519938 1.4986)
			(layers "F.Cu" "F.Mask" "F.Paste")
			(net "TP_CHA_CPU0_DIMM1_FRU_5")
		)
		(pad "232" smd rect
			(at 2.050034 15.724886 270)
			(size 0.519938 1.4986)
			(layers "F.Cu" "F.Mask" "F.Paste")
			(net "TP_CHA_CPU0_DIMM1_FRU_6")
		)
		(pad "233" smd rect
			(at 2.050034 16.575024 270)
			(size 0.519938 1.4986)
			(layers "F.Cu" "F.Mask" "F.Paste")
			(net "GND")
		)
		(pad "234" smd rect
			(at 2.050034 17.424908 270)
			(size 0.519938 1.4986)
			(layers "F.Cu" "F.Mask" "F.Paste")
			(net "M_A_CPU0_SB_CB<6>")
		)
		(pad "235" smd rect
			(at 2.050034 18.275046 270)
			(size 0.519938 1.4986)
			(layers "F.Cu" "F.Mask" "F.Paste")
			(net "GND")
		)
		(pad "236" smd rect
			(at 2.050034 19.12493 270)
			(size 0.519938 1.4986)
			(layers "F.Cu" "F.Mask" "F.Paste")
			(net "M_A_CPU0_SB_CB<7>")
		)
		(pad "237" smd rect
			(at 2.050034 19.975068 270)
			(size 0.519938 1.4986)
			(layers "F.Cu" "F.Mask" "F.Paste")
			(net "GND")
		)
		(pad "238" smd rect
			(at 2.050034 20.824952 270)
			(size 0.519938 1.4986)
			(layers "F.Cu" "F.Mask" "F.Paste")
			(net "M_A_CPU0_SB_DQS_DN<4>")
		)
		(pad "239" smd rect
			(at 2.050034 21.67509 270)
			(size 0.519938 1.4986)
			(layers "F.Cu" "F.Mask" "F.Paste")
			(net "M_A_CPU0_SB_DQS_DP<4>")
		)
		(pad "240" smd rect
			(at 2.050034 22.524974 270)
			(size 0.519938 1.4986)
			(layers "F.Cu" "F.Mask" "F.Paste")
			(net "GND")
		)
		(pad "241" smd rect
			(at 2.050034 23.375112 270)
			(size 0.519938 1.4986)
			(layers "F.Cu" "F.Mask" "F.Paste")
			(net "M_A_CPU0_SB_CB<2>")
		)
		(pad "242" smd rect
			(at 2.050034 24.224996 270)
			(size 0.519938 1.4986)
			(layers "F.Cu" "F.Mask" "F.Paste")
			(net "GND")
		)
		(pad "243" smd rect
			(at 2.050034 25.07488 270)
			(size 0.519938 1.4986)
			(layers "F.Cu" "F.Mask" "F.Paste")
			(net "M_A_CPU0_SB_CB<3>")
		)
		(pad "244" smd rect
			(at 2.050034 25.925018 270)
			(size 0.519938 1.4986)
			(layers "F.Cu" "F.Mask" "F.Paste")
			(net "GND")
		)
		(pad "245" smd rect
			(at 2.050034 26.774902 270)
			(size 0.519938 1.4986)
			(layers "F.Cu" "F.Mask" "F.Paste")
			(net "M_A_CPU0_SB_DQ<2>")
		)
		(pad "246" smd rect
			(at 2.050034 27.62504 270)
			(size 0.519938 1.4986)
			(layers "F.Cu" "F.Mask" "F.Paste")
			(net "GND")
		)
		(pad "247" smd rect
			(at 2.050034 28.474924 270)
			(size 0.519938 1.4986)
			(layers "F.Cu" "F.Mask" "F.Paste")
			(net "M_A_CPU0_SB_DQ<3>")
		)
		(pad "248" smd rect
			(at 2.050034 29.325062 270)
			(size 0.519938 1.4986)
			(layers "F.Cu" "F.Mask" "F.Paste")
			(net "GND")
		)
		(pad "249" smd rect
			(at 2.050034 30.174946 270)
			(size 0.519938 1.4986)
			(layers "F.Cu" "F.Mask" "F.Paste")
			(net "M_A_CPU0_SB_DQS_DN<5>")
		)
		(pad "250" smd rect
			(at 2.050034 31.025084 270)
			(size 0.519938 1.4986)
			(layers "F.Cu" "F.Mask" "F.Paste")
			(net "M_A_CPU0_SB_DQS_DP<5>")
		)
		(pad "251" smd rect
			(at 2.050034 31.874968 270)
			(size 0.519938 1.4986)
			(layers "F.Cu" "F.Mask" "F.Paste")
			(net "GND")
		)
		(pad "252" smd rect
			(at 2.050034 32.725106 270)
			(size 0.519938 1.4986)
			(layers "F.Cu" "F.Mask" "F.Paste")
			(net "M_A_CPU0_SB_DQ<6>")
		)
		(pad "253" smd rect
			(at 2.050034 33.57499 270)
			(size 0.519938 1.4986)
			(layers "F.Cu" "F.Mask" "F.Paste")
			(net "GND")
		)
		(pad "254" smd rect
			(at 2.050034 34.425128 270)
			(size 0.519938 1.4986)
			(layers "F.Cu" "F.Mask" "F.Paste")
			(net "M_A_CPU0_SB_DQ<7>")
		)
		(pad "255" smd rect
			(at 2.050034 35.275012 270)
			(size 0.519938 1.4986)
			(layers "F.Cu" "F.Mask" "F.Paste")
			(net "GND")
		)
		(pad "256" smd rect
			(at 2.050034 36.124896 270)
			(size 0.519938 1.4986)
			(layers "F.Cu" "F.Mask" "F.Paste")
			(net "M_A_CPU0_SB_DQ<10>")
		)
		(pad "257" smd rect
			(at 2.050034 36.975034 270)
			(size 0.519938 1.4986)
			(layers "F.Cu" "F.Mask" "F.Paste")
			(net "GND")
		)
		(pad "258" smd rect
			(at 2.050034 37.824918 270)
			(size 0.519938 1.4986)
			(layers "F.Cu" "F.Mask" "F.Paste")
			(net "M_A_CPU0_SB_DQ<11>")
		)
		(pad "259" smd rect
			(at 2.050034 38.675056 270)
			(size 0.519938 1.4986)
			(layers "F.Cu" "F.Mask" "F.Paste")
			(net "GND")
		)
		(pad "260" smd rect
			(at 2.050034 39.52494 270)
			(size 0.519938 1.4986)
			(layers "F.Cu" "F.Mask" "F.Paste")
			(net "M_A_CPU0_SB_DQS_DN<6>")
		)
		(pad "261" smd rect
			(at 2.050034 40.375078 270)
			(size 0.519938 1.4986)
			(layers "F.Cu" "F.Mask" "F.Paste")
			(net "M_A_CPU0_SB_DQS_DP<6>")
		)
		(pad "262" smd rect
			(at 2.050034 41.224962 270)
			(size 0.519938 1.4986)
			(layers "F.Cu" "F.Mask" "F.Paste")
			(net "GND")
		)
		(pad "263" smd rect
			(at 2.050034 42.0751 270)
			(size 0.519938 1.4986)
			(layers "F.Cu" "F.Mask" "F.Paste")
			(net "M_A_CPU0_SB_DQ<14>")
		)
		(pad "264" smd rect
			(at 2.050034 42.924984 270)
			(size 0.519938 1.4986)
			(layers "F.Cu" "F.Mask" "F.Paste")
			(net "GND")
		)
		(pad "265" smd rect
			(at 2.050034 43.775122 270)
			(size 0.519938 1.4986)
			(layers "F.Cu" "F.Mask" "F.Paste")
			(net "M_A_CPU0_SB_DQ<15>")
		)
		(pad "266" smd rect
			(at 2.050034 44.625006 270)
			(size 0.519938 1.4986)
			(layers "F.Cu" "F.Mask" "F.Paste")
			(net "GND")
		)
		(pad "267" smd rect
			(at 2.050034 45.47489 270)
			(size 0.519938 1.4986)
			(layers "F.Cu" "F.Mask" "F.Paste")
			(net "M_A_CPU0_SB_DQ<18>")
		)
		(pad "268" smd rect
			(at 2.050034 46.325028 270)
			(size 0.519938 1.4986)
			(layers "F.Cu" "F.Mask" "F.Paste")
			(net "GND")
		)
		(pad "269" smd rect
			(at 2.050034 47.174912 270)
			(size 0.519938 1.4986)
			(layers "F.Cu" "F.Mask" "F.Paste")
			(net "M_A_CPU0_SB_DQ<19>")
		)
		(pad "270" smd rect
			(at 2.050034 48.02505 270)
			(size 0.519938 1.4986)
			(layers "F.Cu" "F.Mask" "F.Paste")
			(net "GND")
		)
		(pad "271" smd rect
			(at 2.050034 48.874934 270)
			(size 0.519938 1.4986)
			(layers "F.Cu" "F.Mask" "F.Paste")
			(net "M_A_CPU0_SB_DQS_DN<7>")
		)
		(pad "272" smd rect
			(at 2.050034 49.725072 270)
			(size 0.519938 1.4986)
			(layers "F.Cu" "F.Mask" "F.Paste")
			(net "M_A_CPU0_SB_DQS_DP<7>")
		)
		(pad "273" smd rect
			(at 2.050034 50.574956 270)
			(size 0.519938 1.4986)
			(layers "F.Cu" "F.Mask" "F.Paste")
			(net "GND")
		)
		(pad "274" smd rect
			(at 2.050034 51.425094 270)
			(size 0.519938 1.4986)
			(layers "F.Cu" "F.Mask" "F.Paste")
			(net "M_A_CPU0_SB_DQ<22>")
		)
		(pad "275" smd rect
			(at 2.050034 52.274978 270)
			(size 0.519938 1.4986)
			(layers "F.Cu" "F.Mask" "F.Paste")
			(net "GND")
		)
		(pad "276" smd rect
			(at 2.050034 53.125116 270)
			(size 0.519938 1.4986)
			(layers "F.Cu" "F.Mask" "F.Paste")
			(net "M_A_CPU0_SB_DQ<23>")
		)
		(pad "277" smd rect
			(at 2.050034 53.975 270)
			(size 0.519938 1.4986)
			(layers "F.Cu" "F.Mask" "F.Paste")
			(net "GND")
		)
		(pad "278" smd rect
			(at 2.050034 54.824884 270)
			(size 0.519938 1.4986)
			(layers "F.Cu" "F.Mask" "F.Paste")
			(net "M_A_CPU0_SB_DQ<26>")
		)
		(pad "279" smd rect
			(at 2.050034 55.675022 270)
			(size 0.519938 1.4986)
			(layers "F.Cu" "F.Mask" "F.Paste")
			(net "GND")
		)
		(pad "280" smd rect
			(at 2.050034 56.524906 270)
			(size 0.519938 1.4986)
			(layers "F.Cu" "F.Mask" "F.Paste")
			(net "M_A_CPU0_SB_DQ<27>")
		)
		(pad "281" smd rect
			(at 2.050034 57.375044 270)
			(size 0.519938 1.4986)
			(layers "F.Cu" "F.Mask" "F.Paste")
			(net "GND")
		)
		(pad "282" smd rect
			(at 2.050034 58.224928 270)
			(size 0.519938 1.4986)
			(layers "F.Cu" "F.Mask" "F.Paste")
			(net "M_A_CPU0_SB_DQS_DN<8>")
		)
		(pad "283" smd rect
			(at 2.050034 59.075066 270)
			(size 0.519938 1.4986)
			(layers "F.Cu" "F.Mask" "F.Paste")
			(net "M_A_CPU0_SB_DQS_DP<8>")
		)
		(pad "284" smd rect
			(at 2.050034 59.92495 270)
			(size 0.519938 1.4986)
			(layers "F.Cu" "F.Mask" "F.Paste")
			(net "GND")
		)
		(pad "285" smd rect
			(at 2.050034 60.775088 270)
			(size 0.519938 1.4986)
			(layers "F.Cu" "F.Mask" "F.Paste")
			(net "M_A_CPU0_SB_DQ<30>")
		)
		(pad "286" smd rect
			(at 2.050034 61.624972 270)
			(size 0.519938 1.4986)
			(layers "F.Cu" "F.Mask" "F.Paste")
			(net "GND")
		)
		(pad "287" smd rect
			(at 2.050034 62.47511 270)
			(size 0.519938 1.4986)
			(layers "F.Cu" "F.Mask" "F.Paste")
			(net "M_A_CPU0_SB_DQ<31>")
		)
		(pad "288" smd rect
			(at 2.050034 63.324994 270)
			(size 0.519938 1.4986)
			(layers "F.Cu" "F.Mask" "F.Paste")
			(net "GND")
		)
		(pad "G1" thru_hole oval
			(at 0 -68.97497)
			(size 2.8194 1.5748)
			(drill oval 2.4384 1.1938)
			(layers "*.Cu" "*.Mask")
			(remove_unused_layers no)
			(net "GND")
			(clearance 0.127)
			(thermal_gap 0.127)
		)
		(pad "G2" thru_hole oval
			(at 0 3.875024)
			(size 2.8194 1.5748)
			(drill oval 2.4384 1.1938)
			(layers "*.Cu" "*.Mask")
			(remove_unused_layers no)
			(net "GND")
			(clearance 0.127)
			(thermal_gap 0.127)
		)
		(pad "G3" thru_hole oval
			(at 0 68.97497)
			(size 2.8194 1.5748)
			(drill oval 2.4384 1.1938)
			(layers "*.Cu" "*.Mask")
			(remove_unused_layers no)
			(net "GND")
			(clearance 0.127)
			(thermal_gap 0.127)
		)
	)
)
